(kicad_pcb
	(version 20260206)
	(generator "pcbnew")
	(generator_version "10.0")
	(general
		(thickness 1.6)
		(legacy_teardrops no)
	)
	(paper "A4")
	(title_block
		(title "peb — Lightning_PEB_BRD.brd")
		(comment 1 "Lightning (Wiwynn / Facebook NVMe JBOF) / footprints 2402-2409 of 2563")
	)
	(layers
		(0 "F.Cu" signal "TOP")
		(4 "In1.Cu" signal "L2GND")
		(6 "In2.Cu" signal "L3")
		(8 "In3.Cu" signal "L4VCC")
		(10 "In4.Cu" signal "L5VCC")
		(12 "In5.Cu" signal "L6")
		(14 "In6.Cu" signal "L7GND")
		(2 "B.Cu" signal "BOTTOM")
		(9 "F.Adhes" user "F.Adhesive")
		(11 "B.Adhes" user "B.Adhesive")
		(13 "F.Paste" user "Package Geometry/Pastemask Top")
		(15 "B.Paste" user "Package Geometry/Pastemask Bottom")
		(5 "F.SilkS" user "Ref Des/Silkscreen Top")
		(7 "B.SilkS" user "Ref Des/Silkscreen Bottom")
		(1 "F.Mask" user "Board Geometry/Soldermask Top")
		(3 "B.Mask" user "Board Geometry/Soldermask Bottom")
		(17 "Dwgs.User" user "User.Drawings")
		(19 "Cmts.User" user "User.Comments")
		(21 "Eco1.User" user "User.Eco1")
		(23 "Eco2.User" user "User.Eco2")
		(25 "Edge.Cuts" user "Board Geometry/Outline")
		(27 "Margin" user)
		(31 "F.CrtYd" user "Package Geometry/Place Bound Top")
		(29 "B.CrtYd" user "Package Geometry/Place Bound Bottom")
		(35 "F.Fab" user "Ref Des/Assembly Top")
		(33 "B.Fab" user "Ref Des/Assembly Bottom")
	)
	(footprint ""
		(layer "B.Cu")
		(at 249.605038 -60.071)
		(property "Reference" "C600"
			(at 0 0 0)
			(layer "B.SilkS")
			(hide yes)
			(effects
				(font
					(size 1.27 1.27)
				)
				(justify mirror)
			)
		)
		(property "Value" "SCD1U16V1KX-1-GP"
			(at 2.8321 -1.7399 0)
			(unlocked yes)
			(layer "B.Fab")
			(hide yes)
			(effects
				(font
					(size 1.016 1.016)
					(thickness 0.1524)
				)
				(justify mirror)
			)
		)
		(property "Device Type" "C0201H13"
			(at 2.8321 -3.2639 0)
			(unlocked yes)
			(layer "B.Fab")
			(hide yes)
			(effects
				(font
					(size 1.016 1.016)
					(thickness 0.1524)
				)
				(justify mirror)
			)
		)
		(duplicate_pad_numbers_are_jumpers no)
		(fp_rect
			(start 0.2794 0.6477)
			(end -0.2794 -0.6477)
			(stroke
				(width 0)
				(type default)
			)
			(fill no)
			(layer "B.CrtYd")
		)
		(fp_rect
			(start 0.2794 0.6477)
			(end -0.2794 -0.6477)
			(stroke
				(width 0)
				(type default)
			)
			(fill no)
			(layer "B.Fab")
		)
		(pad "1" smd custom
			(at 0 -0.2794 180)
			(size 0.0762 0.0762)
			(layers "B.Cu" "B.Mask" "B.Paste")
			(net "DUT_AVD_PCIE")
			(options
				(clearance outline)
				(anchor circle)
			)
			(primitives
				(gr_poly
					(pts
						(arc
							(start 0.1524 0.127)
							(mid 0.137521 0.162921)
							(end 0.1016 0.1778)
						)
						(arc
							(start -0.1016 0.1778)
							(mid -0.137521 0.162921)
							(end -0.1524 0.127)
						)
						(arc
							(start -0.1524 -0.127)
							(mid -0.137521 -0.162921)
							(end -0.1016 -0.1778)
						)
						(arc
							(start 0.1016 -0.1778)
							(mid 0.137521 -0.162921)
							(end 0.1524 -0.127)
						)
					)
					(width 0)
					(fill yes)
				)
			)
		)
		(pad "2" smd custom
			(at 0 0.2794 180)
			(size 0.0762 0.0762)
			(layers "B.Cu" "B.Mask" "B.Paste")
			(net "GND")
			(options
				(clearance outline)
				(anchor circle)
			)
			(primitives
				(gr_poly
					(pts
						(arc
							(start 0.1524 0.127)
							(mid 0.137521 0.162921)
							(end 0.1016 0.1778)
						)
						(arc
							(start -0.1016 0.1778)
							(mid -0.137521 0.162921)
							(end -0.1524 0.127)
						)
						(arc
							(start -0.1524 -0.127)
							(mid -0.137521 -0.162921)
							(end -0.1016 -0.1778)
						)
						(arc
							(start 0.1016 -0.1778)
							(mid 0.137521 -0.162921)
							(end 0.1524 -0.127)
						)
					)
					(width 0)
					(fill yes)
				)
			)
		)
	)
	(footprint ""
		(layer "B.Cu")
		(at 246.599964 -34.99993)
		(property "Reference" "TP294"
			(at 0 0 0)
			(layer "B.SilkS")
			(hide yes)
			(effects
				(font
					(size 1.27 1.27)
				)
				(justify mirror)
			)
		)
		(property "Value" "TPAD28-2-GP"
			(at 0.0127 -1.6637 0)
			(unlocked yes)
			(layer "B.Fab")
			(hide yes)
			(effects
				(font
					(size 1.016 1.016)
					(thickness 0.1524)
				)
				(justify mirror)
			)
		)
		(property "Device Type" "TPAD28"
			(at 0.0127 -3.1877 0)
			(unlocked yes)
			(layer "B.Fab")
			(hide yes)
			(effects
				(font
					(size 1.016 1.016)
					(thickness 0.1524)
				)
				(justify mirror)
			)
		)
		(duplicate_pad_numbers_are_jumpers no)
		(fp_poly
			(pts
				(arc
					(start 0.3556 0)
					(mid -0.3556 0)
					(end 0.3556 0)
				)
			)
			(stroke
				(width 0)
				(type default)
			)
			(fill no)
			(layer "B.CrtYd")
		)
		(fp_poly
			(pts
				(arc
					(start 0.6096 0)
					(mid -0.6096 0)
					(end 0.6096 0)
				)
			)
			(stroke
				(width 0)
				(type default)
			)
			(fill no)
			(layer "B.Fab")
		)
		(pad "1" smd circle
			(at 0 0 180)
			(size 0.7112 0.7112)
			(layers "B.Cu" "B.Mask" "B.Paste")
			(net "TWI_SRST#7")
		)
	)
	(footprint ""
		(layer "B.Cu")
		(at 247.1166 -48.9966 -90)
		(property "Reference" "C445"
			(at 0 0 90)
			(layer "B.SilkS")
			(hide yes)
			(effects
				(font
					(size 1.27 1.27)
				)
				(justify mirror)
			)
		)
		(property "Value" "SCD1U16V1KX-1-GP"
			(at 2.8321 -1.7399 270)
			(unlocked yes)
			(layer "B.Fab")
			(hide yes)
			(effects
				(font
					(size 1.016 1.016)
					(thickness 0.1524)
				)
				(justify mirror)
			)
		)
		(property "Device Type" "C0201H13"
			(at 2.8321 -3.2639 270)
			(unlocked yes)
			(layer "B.Fab")
			(hide yes)
			(effects
				(font
					(size 1.016 1.016)
					(thickness 0.1524)
				)
				(justify mirror)
			)
		)
		(duplicate_pad_numbers_are_jumpers no)
		(fp_rect
			(start 0.2794 0.6477)
			(end -0.2794 -0.6477)
			(stroke
				(width 0)
				(type default)
			)
			(fill no)
			(layer "B.CrtYd")
		)
		(fp_rect
			(start 0.2794 0.6477)
			(end -0.2794 -0.6477)
			(stroke
				(width 0)
				(type default)
			)
			(fill no)
			(layer "B.Fab")
		)
		(pad "1" smd custom
			(at 0 -0.2794 90)
			(size 0.0762 0.0762)
			(layers "B.Cu" "B.Mask" "B.Paste")
			(net "DUT_VDD")
			(options
				(clearance outline)
				(anchor circle)
			)
			(primitives
				(gr_poly
					(pts
						(arc
							(start 0.1524 0.127)
							(mid 0.137521 0.162921)
							(end 0.1016 0.1778)
						)
						(arc
							(start -0.1016 0.1778)
							(mid -0.137521 0.162921)
							(end -0.1524 0.127)
						)
						(arc
							(start -0.1524 -0.127)
							(mid -0.137521 -0.162921)
							(end -0.1016 -0.1778)
						)
						(arc
							(start 0.1016 -0.1778)
							(mid 0.137521 -0.162921)
							(end 0.1524 -0.127)
						)
					)
					(width 0)
					(fill yes)
				)
			)
		)
		(pad "2" smd custom
			(at 0 0.2794 90)
			(size 0.0762 0.0762)
			(layers "B.Cu" "B.Mask" "B.Paste")
			(net "GND")
			(options
				(clearance outline)
				(anchor circle)
			)
			(primitives
				(gr_poly
					(pts
						(arc
							(start 0.1524 0.127)
							(mid 0.137521 0.162921)
							(end 0.1016 0.1778)
						)
						(arc
							(start -0.1016 0.1778)
							(mid -0.137521 0.162921)
							(end -0.1524 0.127)
						)
						(arc
							(start -0.1524 -0.127)
							(mid -0.137521 -0.162921)
							(end -0.1016 -0.1778)
						)
						(arc
							(start 0.1016 -0.1778)
							(mid 0.137521 -0.162921)
							(end 0.1524 -0.127)
						)
					)
					(width 0)
					(fill yes)
				)
			)
		)
	)
	(footprint ""
		(layer "B.Cu")
		(at 35.433 -118.491 -90)
		(property "Reference" "TP220"
			(at 0 0 90)
			(layer "B.SilkS")
			(hide yes)
			(effects
				(font
					(size 1.27 1.27)
				)
				(justify mirror)
			)
		)
		(property "Value" "TPAD28-2-GP"
			(at 0.0127 -1.6637 270)
			(unlocked yes)
			(layer "B.Fab")
			(hide yes)
			(effects
				(font
					(size 1.016 1.016)
					(thickness 0.1524)
				)
				(justify mirror)
			)
		)
		(property "Device Type" "TPAD28"
			(at 0.0127 -3.1877 270)
			(unlocked yes)
			(layer "B.Fab")
			(hide yes)
			(effects
				(font
					(size 1.016 1.016)
					(thickness 0.1524)
				)
				(justify mirror)
			)
		)
		(duplicate_pad_numbers_are_jumpers no)
		(fp_poly
			(pts
				(arc
					(start 0 -0.3556)
					(mid 0 0.3556)
					(end 0 -0.3556)
				)
			)
			(stroke
				(width 0)
				(type default)
			)
			(fill no)
			(layer "B.CrtYd")
		)
		(fp_poly
			(pts
				(arc
					(start 0 -0.6096)
					(mid 0 0.6096)
					(end 0 -0.6096)
				)
			)
			(stroke
				(width 0)
				(type default)
			)
			(fill no)
			(layer "B.Fab")
		)
		(pad "1" smd circle
			(at 0 0 90)
			(size 0.7112 0.7112)
			(layers "B.Cu" "B.Mask" "B.Paste")
			(net "TP_GPIOE6")
		)
	)
	(footprint ""
		(layer "B.Cu")
		(at 335.153 -179.705)
		(property "Reference" "R209"
			(at 0 0 0)
			(layer "B.SilkS")
			(hide yes)
			(effects
				(font
					(size 1.27 1.27)
				)
				(justify mirror)
			)
		)
		(property "Value" "4K7R2F-GP"
			(at -0.064008 -3.993896 0)
			(unlocked yes)
			(layer "B.Fab")
			(hide yes)
			(effects
				(font
					(size 1.016 1.016)
					(thickness 0.1524)
				)
				(justify mirror)
			)
		)
		(property "Device Type" "R402H16"
			(at -0.064008 -5.517896 0)
			(unlocked yes)
			(layer "B.Fab")
			(hide yes)
			(effects
				(font
					(size 1.016 1.016)
					(thickness 0.1524)
				)
				(justify mirror)
			)
		)
		(duplicate_pad_numbers_are_jumpers no)
		(fp_line
			(start -0.508 -0.9398)
			(end 0.508 -0.9398)
			(stroke
				(width 0.1524)
				(type default)
			)
			(layer "B.SilkS")
		)
		(fp_line
			(start 0.508 -0.9398)
			(end 0.508 0.9398)
			(stroke
				(width 0.1524)
				(type default)
			)
			(layer "B.SilkS")
		)
		(fp_rect
			(start 0.508 0.9398)
			(end -0.508 -0.9398)
			(stroke
				(width 0)
				(type default)
			)
			(fill no)
			(layer "B.CrtYd")
		)
		(fp_rect
			(start 0.508 0.9398)
			(end -0.508 -0.9398)
			(stroke
				(width 0)
				(type default)
			)
			(fill no)
			(layer "B.Fab")
		)
		(pad "1" smd custom
			(at 0 -0.4445 180)
			(size 0.1397 0.1397)
			(layers "B.Cu" "B.Mask" "B.Paste")
			(net "BMC_SSD_RST#0_A9")
			(options
				(clearance outline)
				(anchor circle)
			)
			(primitives
				(gr_poly
					(pts
						(arc
							(start -0.1778 0.2794)
							(mid -0.249642 0.249642)
							(end -0.2794 0.1778)
						)
						(arc
							(start -0.2794 -0.1778)
							(mid -0.249642 -0.249642)
							(end -0.1778 -0.2794)
						)
						(arc
							(start 0.1778 -0.2794)
							(mid 0.249642 -0.249642)
							(end 0.2794 -0.1778)
						)
						(arc
							(start 0.2794 0.1778)
							(mid 0.249642 0.249642)
							(end 0.1778 0.2794)
						)
					)
					(width 0)
					(fill yes)
				)
			)
		)
		(pad "2" smd custom
			(at 0 0.4445 180)
			(size 0.1397 0.1397)
			(layers "B.Cu" "B.Mask" "B.Paste")
			(net "P3V3_STBY")
			(options
				(clearance outline)
				(anchor circle)
			)
			(primitives
				(gr_poly
					(pts
						(arc
							(start -0.1778 0.2794)
							(mid -0.249642 0.249642)
							(end -0.2794 0.1778)
						)
						(arc
							(start -0.2794 -0.1778)
							(mid -0.249642 -0.249642)
							(end -0.1778 -0.2794)
						)
						(arc
							(start 0.1778 -0.2794)
							(mid 0.249642 -0.249642)
							(end 0.2794 -0.1778)
						)
						(arc
							(start 0.2794 0.1778)
							(mid 0.249642 0.249642)
							(end 0.1778 0.2794)
						)
					)
					(width 0)
					(fill yes)
				)
			)
		)
	)
	(footprint ""
		(layer "B.Cu")
		(at 239.1664 -48.9966 90)
		(property "Reference" "C35"
			(at 0 0 90)
			(layer "B.SilkS")
			(hide yes)
			(effects
				(font
					(size 1.27 1.27)
				)
				(justify mirror)
			)
		)
		(property "Value" "SCD1U16V1KX-1-GP"
			(at 2.8321 -1.7399 90)
			(unlocked yes)
			(layer "B.Fab")
			(hide yes)
			(effects
				(font
					(size 1.016 1.016)
					(thickness 0.1524)
				)
				(justify mirror)
			)
		)
		(property "Device Type" "C0201H13"
			(at 2.8321 -3.2639 90)
			(unlocked yes)
			(layer "B.Fab")
			(hide yes)
			(effects
				(font
					(size 1.016 1.016)
					(thickness 0.1524)
				)
				(justify mirror)
			)
		)
		(duplicate_pad_numbers_are_jumpers no)
		(fp_rect
			(start 0.2794 0.6477)
			(end -0.2794 -0.6477)
			(stroke
				(width 0)
				(type default)
			)
			(fill no)
			(layer "B.CrtYd")
		)
		(fp_rect
			(start 0.2794 0.6477)
			(end -0.2794 -0.6477)
			(stroke
				(width 0)
				(type default)
			)
			(fill no)
			(layer "B.Fab")
		)
		(pad "1" smd custom
			(at 0 -0.2794 270)
			(size 0.0762 0.0762)
			(layers "B.Cu" "B.Mask" "B.Paste")
			(net "DUT_VDD")
			(options
				(clearance outline)
				(anchor circle)
			)
			(primitives
				(gr_poly
					(pts
						(arc
							(start 0.1524 0.127)
							(mid 0.137521 0.162921)
							(end 0.1016 0.1778)
						)
						(arc
							(start -0.1016 0.1778)
							(mid -0.137521 0.162921)
							(end -0.1524 0.127)
						)
						(arc
							(start -0.1524 -0.127)
							(mid -0.137521 -0.162921)
							(end -0.1016 -0.1778)
						)
						(arc
							(start 0.1016 -0.1778)
							(mid 0.137521 -0.162921)
							(end 0.1524 -0.127)
						)
					)
					(width 0)
					(fill yes)
				)
			)
		)
		(pad "2" smd custom
			(at 0 0.2794 270)
			(size 0.0762 0.0762)
			(layers "B.Cu" "B.Mask" "B.Paste")
			(net "GND")
			(options
				(clearance outline)
				(anchor circle)
			)
			(primitives
				(gr_poly
					(pts
						(arc
							(start 0.1524 0.127)
							(mid 0.137521 0.162921)
							(end 0.1016 0.1778)
						)
						(arc
							(start -0.1016 0.1778)
							(mid -0.137521 0.162921)
							(end -0.1524 0.127)
						)
						(arc
							(start -0.1524 -0.127)
							(mid -0.137521 -0.162921)
							(end -0.1016 -0.1778)
						)
						(arc
							(start 0.1016 -0.1778)
							(mid 0.137521 -0.162921)
							(end 0.1524 -0.127)
						)
					)
					(width 0)
					(fill yes)
				)
			)
		)
	)
	(footprint ""
		(layer "B.Cu")
		(at 24.13 -119.9896 -90)
		(property "Reference" "R9024"
			(at 0 0 90)
			(layer "B.SilkS")
			(hide yes)
			(effects
				(font
					(size 1.27 1.27)
				)
				(justify mirror)
			)
		)
		(property "Value" "191R2F-GP"
			(at -0.064008 -3.993896 270)
			(unlocked yes)
			(layer "B.Fab")
			(hide yes)
			(effects
				(font
					(size 1.016 1.016)
					(thickness 0.1524)
				)
				(justify mirror)
			)
		)
		(property "Device Type" "R402H16"
			(at -0.064008 -5.517896 270)
			(unlocked yes)
			(layer "B.Fab")
			(hide yes)
			(effects
				(font
					(size 1.016 1.016)
					(thickness 0.1524)
				)
				(justify mirror)
			)
		)
		(duplicate_pad_numbers_are_jumpers no)
		(fp_line
			(start -0.508 -0.9398)
			(end 0.508 -0.9398)
			(stroke
				(width 0.1524)
				(type default)
			)
			(layer "B.SilkS")
		)
		(fp_line
			(start 0.508 -0.9398)
			(end 0.508 0.9398)
			(stroke
				(width 0.1524)
				(type default)
			)
			(layer "B.SilkS")
		)
		(fp_rect
			(start 0.508 0.9398)
			(end -0.508 -0.9398)
			(stroke
				(width 0)
				(type default)
			)
			(fill no)
			(layer "B.CrtYd")
		)
		(fp_rect
			(start 0.508 0.9398)
			(end -0.508 -0.9398)
			(stroke
				(width 0)
				(type default)
			)
			(fill no)
			(layer "B.Fab")
		)
		(pad "1" smd custom
			(at 0 -0.4445 90)
			(size 0.1397 0.1397)
			(layers "B.Cu" "B.Mask" "B.Paste")
			(net "BMC_PEREXT")
			(options
				(clearance outline)
				(anchor circle)
			)
			(primitives
				(gr_poly
					(pts
						(arc
							(start -0.1778 0.2794)
							(mid -0.249642 0.249642)
							(end -0.2794 0.1778)
						)
						(arc
							(start -0.2794 -0.1778)
							(mid -0.249642 -0.249642)
							(end -0.1778 -0.2794)
						)
						(arc
							(start 0.1778 -0.2794)
							(mid 0.249642 -0.249642)
							(end 0.2794 -0.1778)
						)
						(arc
							(start 0.2794 0.1778)
							(mid 0.249642 0.249642)
							(end 0.1778 0.2794)
						)
					)
					(width 0)
					(fill yes)
				)
			)
		)
		(pad "2" smd custom
			(at 0 0.4445 90)
			(size 0.1397 0.1397)
			(layers "B.Cu" "B.Mask" "B.Paste")
			(net "GND")
			(options
				(clearance outline)
				(anchor circle)
			)
			(primitives
				(gr_poly
					(pts
						(arc
							(start -0.1778 0.2794)
							(mid -0.249642 0.249642)
							(end -0.2794 0.1778)
						)
						(arc
							(start -0.2794 -0.1778)
							(mid -0.249642 -0.249642)
							(end -0.1778 -0.2794)
						)
						(arc
							(start 0.1778 -0.2794)
							(mid 0.249642 -0.249642)
							(end 0.2794 -0.1778)
						)
						(arc
							(start 0.2794 0.1778)
							(mid 0.249642 0.249642)
							(end 0.1778 0.2794)
						)
					)
					(width 0)
					(fill yes)
				)
			)
		)
	)
	(footprint ""
		(layer "B.Cu")
		(at 140.589 -34.059876 90)
		(property "Reference" "C224"
			(at 0 0 90)
			(layer "B.SilkS")
			(hide yes)
			(effects
				(font
					(size 1.27 1.27)
				)
				(justify mirror)
			)
		)
		(property "Value" "SCD1U10V2KX-5GP"
			(at -1.1811 -2.7051 90)
			(unlocked yes)
			(layer "B.Fab")
			(hide yes)
			(effects
				(font
					(size 1.016 1.016)
					(thickness 0.1524)
				)
				(justify mirror)
			)
		)
		(property "Device Type" "C402H22"
			(at -1.1811 -4.2291 90)
			(unlocked yes)
			(layer "B.Fab")
			(hide yes)
			(effects
				(font
					(size 1.016 1.016)
					(thickness 0.1524)
				)
				(justify mirror)
			)
		)
		(duplicate_pad_numbers_are_jumpers no)
		(fp_rect
			(start 0.4318 0.9525)
			(end -0.4318 -0.9525)
			(stroke
				(width 0)
				(type default)
			)
			(fill no)
			(layer "B.CrtYd")
		)
		(fp_rect
			(start 0.4318 0.9525)
			(end -0.4318 -0.9525)
			(stroke
				(width 0)
				(type default)
			)
			(fill no)
			(layer "B.Fab")
		)
		(pad "1" smd custom
			(at 0 -0.4445 270)
			(size 0.1524 0.1524)
			(layers "B.Cu" "B.Mask" "B.Paste")
			(net "GND")
			(options
				(clearance outline)
				(anchor circle)
			)
			(primitives
				(gr_poly
					(pts
						(arc
							(start 0.3048 0.2032)
							(mid 0.275042 0.275042)
							(end 0.2032 0.3048)
						)
						(arc
							(start -0.2032 0.3048)
							(mid -0.275042 0.275042)
							(end -0.3048 0.2032)
						)
						(arc
							(start -0.3048 -0.2032)
							(mid -0.275042 -0.275042)
							(end -0.2032 -0.3048)
						)
						(arc
							(start 0.2032 -0.3048)
							(mid 0.275042 -0.275042)
							(end 0.3048 -0.2032)
						)
					)
					(width 0)
					(fill yes)
				)
			)
		)
		(pad "2" smd custom
			(at 0 0.4445 270)
			(size 0.1524 0.1524)
			(layers "B.Cu" "B.Mask" "B.Paste")
			(net "P3V3_STBY")
			(options
				(clearance outline)
				(anchor circle)
			)
			(primitives
				(gr_poly
					(pts
						(arc
							(start 0.3048 0.2032)
							(mid 0.275042 0.275042)
							(end 0.2032 0.3048)
						)
						(arc
							(start -0.2032 0.3048)
							(mid -0.275042 0.275042)
							(end -0.3048 0.2032)
						)
						(arc
							(start -0.3048 -0.2032)
							(mid -0.275042 -0.275042)
							(end -0.2032 -0.3048)
						)
						(arc
							(start 0.2032 -0.3048)
							(mid 0.275042 -0.275042)
							(end 0.3048 -0.2032)
						)
					)
					(width 0)
					(fill yes)
				)
			)
		)
	)
)
